(kicad_pcb
	(version 20260206)
	(generator "pcbnew")
	(generator_version "10.0")
	(general
		(thickness 1.6)
		(legacy_teardrops no)
	)
	(paper "A4")
	(title_block
		(title "04192023_DAF0TMB3IC0_F0TG_MB_C_brd_V02_OCP.brd")
		(comment 1 "Grand Teton / footprint 1808 of 8354 (J16), pads 1-113 of 291")
	)
	(layers
		(0 "F.Cu" signal "TOP")
		(4 "In1.Cu" signal "GND")
		(6 "In2.Cu" signal "IN1")
		(8 "In3.Cu" signal "GND1")
		(10 "In4.Cu" signal "IN2")
		(12 "In5.Cu" signal "GND2")
		(14 "In6.Cu" signal "IN3")
		(16 "In7.Cu" signal "GND3")
		(18 "In8.Cu" signal "VCC")
		(20 "In9.Cu" signal "VCC1")
		(22 "In10.Cu" signal "GND4")
		(24 "In11.Cu" signal "IN4")
		(26 "In12.Cu" signal "GND5")
		(28 "In13.Cu" signal "IN5")
		(30 "In14.Cu" signal "GND6")
		(32 "In15.Cu" signal "IN6")
		(34 "In16.Cu" signal "GND7")
		(2 "B.Cu" signal "BOTTOM")
		(9 "F.Adhes" user "F.Adhesive")
		(11 "B.Adhes" user "B.Adhesive")
		(13 "F.Paste" user "Package Geometry/Pastemask Top")
		(15 "B.Paste" user "Package Geometry/Pastemask Bottom")
		(5 "F.SilkS" user "Ref Des/Silkscreen Top")
		(7 "B.SilkS" user "Ref Des/Silkscreen Bottom")
		(1 "F.Mask" user "Board Geometry/Soldermask Top")
		(3 "B.Mask" user "Board Geometry/Soldermask Bottom")
		(17 "Dwgs.User" user "User.Drawings")
		(19 "Cmts.User" user "User.Comments")
		(21 "Eco1.User" user "User.Eco1")
		(23 "Eco2.User" user "User.Eco2")
		(25 "Edge.Cuts" user "Board Geometry/Outline")
		(27 "Margin" user)
		(31 "F.CrtYd" user "Package Geometry/Place Bound Top")
		(29 "B.CrtYd" user "Package Geometry/Place Bound Bottom")
		(35 "F.Fab" user "Ref Des/Assembly Top")
		(33 "B.Fab" user "Ref Des/Assembly Bottom")
	)
	(footprint ""
		(layer "F.Cu")
		(at 414.418018 -255.560068 180)
		(property "Reference" "J16"
			(at 1.474216 81.889092 0)
			(unlocked yes)
			(layer "F.SilkS")
			(effects
				(font
					(size 0.7874 0.5842)
					(thickness 0.1524)
				)
			)
		)
		(property "Value" ""
			(at 0 0 180)
			(layer "F.Fab")
			(effects
				(font
					(size 1.27 1.27)
				)
			)
		)
		(duplicate_pad_numbers_are_jumpers no)
		(pad "1" smd rect
			(at -2.050034 -63.324994 90)
			(size 0.519938 1.4986)
			(layers "F.Cu" "F.Mask" "F.Paste")
			(net "P12V_MEM_CPU0")
		)
		(pad "2" smd rect
			(at -2.050034 -62.47511 90)
			(size 0.519938 1.4986)
			(layers "F.Cu" "F.Mask" "F.Paste")
			(net "Net_2333")
		)
		(pad "3" smd rect
			(at -2.050034 -61.624972 90)
			(size 0.519938 1.4986)
			(layers "F.Cu" "F.Mask" "F.Paste")
			(net "P3V3_AUX")
		)
		(pad "4" smd rect
			(at -2.050034 -60.775088 90)
			(size 0.519938 1.4986)
			(layers "F.Cu" "F.Mask" "F.Paste")
			(net "I3C_SPD_DDRG_CPU0_SCL")
		)
		(pad "5" smd rect
			(at -2.050034 -59.92495 90)
			(size 0.519938 1.4986)
			(layers "F.Cu" "F.Mask" "F.Paste")
			(net "I3C_SPD_DDRG_CPU0_SDA")
		)
		(pad "6" smd rect
			(at -2.050034 -59.075066 90)
			(size 0.519938 1.4986)
			(layers "F.Cu" "F.Mask" "F.Paste")
			(net "GND")
		)
		(pad "7" smd rect
			(at -2.050034 -58.224928 90)
			(size 0.519938 1.4986)
			(layers "F.Cu" "F.Mask" "F.Paste")
			(net "M_G_CPU0_SA_DQ<0>")
		)
		(pad "8" smd rect
			(at -2.050034 -57.375044 90)
			(size 0.519938 1.4986)
			(layers "F.Cu" "F.Mask" "F.Paste")
			(net "GND")
		)
		(pad "9" smd rect
			(at -2.050034 -56.524906 90)
			(size 0.519938 1.4986)
			(layers "F.Cu" "F.Mask" "F.Paste")
			(net "M_G_CPU0_SA_DQ<1>")
		)
		(pad "10" smd rect
			(at -2.050034 -55.675022 90)
			(size 0.519938 1.4986)
			(layers "F.Cu" "F.Mask" "F.Paste")
			(net "GND")
		)
		(pad "11" smd rect
			(at -2.050034 -54.824884 90)
			(size 0.519938 1.4986)
			(layers "F.Cu" "F.Mask" "F.Paste")
			(net "M_G_CPU0_SA_DQS_DP<0>")
		)
		(pad "12" smd rect
			(at -2.050034 -53.975 90)
			(size 0.519938 1.4986)
			(layers "F.Cu" "F.Mask" "F.Paste")
			(net "M_G_CPU0_SA_DQS_DN<0>")
		)
		(pad "13" smd rect
			(at -2.050034 -53.125116 90)
			(size 0.519938 1.4986)
			(layers "F.Cu" "F.Mask" "F.Paste")
			(net "GND")
		)
		(pad "14" smd rect
			(at -2.050034 -52.274978 90)
			(size 0.519938 1.4986)
			(layers "F.Cu" "F.Mask" "F.Paste")
			(net "M_G_CPU0_SA_DQ<4>")
		)
		(pad "15" smd rect
			(at -2.050034 -51.425094 90)
			(size 0.519938 1.4986)
			(layers "F.Cu" "F.Mask" "F.Paste")
			(net "GND")
		)
		(pad "16" smd rect
			(at -2.050034 -50.574956 90)
			(size 0.519938 1.4986)
			(layers "F.Cu" "F.Mask" "F.Paste")
			(net "M_G_CPU0_SA_DQ<5>")
		)
		(pad "17" smd rect
			(at -2.050034 -49.725072 90)
			(size 0.519938 1.4986)
			(layers "F.Cu" "F.Mask" "F.Paste")
			(net "GND")
		)
		(pad "18" smd rect
			(at -2.050034 -48.874934 90)
			(size 0.519938 1.4986)
			(layers "F.Cu" "F.Mask" "F.Paste")
			(net "M_G_CPU0_SA_DQ<8>")
		)
		(pad "19" smd rect
			(at -2.050034 -48.02505 90)
			(size 0.519938 1.4986)
			(layers "F.Cu" "F.Mask" "F.Paste")
			(net "GND")
		)
		(pad "20" smd rect
			(at -2.050034 -47.174912 90)
			(size 0.519938 1.4986)
			(layers "F.Cu" "F.Mask" "F.Paste")
			(net "M_G_CPU0_SA_DQ<9>")
		)
		(pad "21" smd rect
			(at -2.050034 -46.325028 90)
			(size 0.519938 1.4986)
			(layers "F.Cu" "F.Mask" "F.Paste")
			(net "GND")
		)
		(pad "22" smd rect
			(at -2.050034 -45.47489 90)
			(size 0.519938 1.4986)
			(layers "F.Cu" "F.Mask" "F.Paste")
			(net "M_G_CPU0_SA_DQS_DP<1>")
		)
		(pad "23" smd rect
			(at -2.050034 -44.625006 90)
			(size 0.519938 1.4986)
			(layers "F.Cu" "F.Mask" "F.Paste")
			(net "M_G_CPU0_SA_DQS_DN<1>")
		)
		(pad "24" smd rect
			(at -2.050034 -43.775122 90)
			(size 0.519938 1.4986)
			(layers "F.Cu" "F.Mask" "F.Paste")
			(net "GND")
		)
		(pad "25" smd rect
			(at -2.050034 -42.924984 90)
			(size 0.519938 1.4986)
			(layers "F.Cu" "F.Mask" "F.Paste")
			(net "M_G_CPU0_SA_DQ<12>")
		)
		(pad "26" smd rect
			(at -2.050034 -42.0751 90)
			(size 0.519938 1.4986)
			(layers "F.Cu" "F.Mask" "F.Paste")
			(net "GND")
		)
		(pad "27" smd rect
			(at -2.050034 -41.224962 90)
			(size 0.519938 1.4986)
			(layers "F.Cu" "F.Mask" "F.Paste")
			(net "M_G_CPU0_SA_DQ<13>")
		)
		(pad "28" smd rect
			(at -2.050034 -40.375078 90)
			(size 0.519938 1.4986)
			(layers "F.Cu" "F.Mask" "F.Paste")
			(net "GND")
		)
		(pad "29" smd rect
			(at -2.050034 -39.52494 90)
			(size 0.519938 1.4986)
			(layers "F.Cu" "F.Mask" "F.Paste")
			(net "M_G_CPU0_SA_DQ<16>")
		)
		(pad "30" smd rect
			(at -2.050034 -38.675056 90)
			(size 0.519938 1.4986)
			(layers "F.Cu" "F.Mask" "F.Paste")
			(net "GND")
		)
		(pad "31" smd rect
			(at -2.050034 -37.824918 90)
			(size 0.519938 1.4986)
			(layers "F.Cu" "F.Mask" "F.Paste")
			(net "M_G_CPU0_SA_DQ<17>")
		)
		(pad "32" smd rect
			(at -2.050034 -36.975034 90)
			(size 0.519938 1.4986)
			(layers "F.Cu" "F.Mask" "F.Paste")
			(net "GND")
		)
		(pad "33" smd rect
			(at -2.050034 -36.124896 90)
			(size 0.519938 1.4986)
			(layers "F.Cu" "F.Mask" "F.Paste")
			(net "M_G_CPU0_SA_DQS_DP<2>")
		)
		(pad "34" smd rect
			(at -2.050034 -35.275012 90)
			(size 0.519938 1.4986)
			(layers "F.Cu" "F.Mask" "F.Paste")
			(net "M_G_CPU0_SA_DQS_DN<2>")
		)
		(pad "35" smd rect
			(at -2.050034 -34.425128 90)
			(size 0.519938 1.4986)
			(layers "F.Cu" "F.Mask" "F.Paste")
			(net "GND")
		)
		(pad "36" smd rect
			(at -2.050034 -33.57499 90)
			(size 0.519938 1.4986)
			(layers "F.Cu" "F.Mask" "F.Paste")
			(net "M_G_CPU0_SA_DQ<20>")
		)
		(pad "37" smd rect
			(at -2.050034 -32.725106 90)
			(size 0.519938 1.4986)
			(layers "F.Cu" "F.Mask" "F.Paste")
			(net "GND")
		)
		(pad "38" smd rect
			(at -2.050034 -31.874968 90)
			(size 0.519938 1.4986)
			(layers "F.Cu" "F.Mask" "F.Paste")
			(net "M_G_CPU0_SA_DQ<21>")
		)
		(pad "39" smd rect
			(at -2.050034 -31.025084 90)
			(size 0.519938 1.4986)
			(layers "F.Cu" "F.Mask" "F.Paste")
			(net "GND")
		)
		(pad "40" smd rect
			(at -2.050034 -30.174946 90)
			(size 0.519938 1.4986)
			(layers "F.Cu" "F.Mask" "F.Paste")
			(net "M_G_CPU0_SA_DQ<24>")
		)
		(pad "41" smd rect
			(at -2.050034 -29.325062 90)
			(size 0.519938 1.4986)
			(layers "F.Cu" "F.Mask" "F.Paste")
			(net "GND")
		)
		(pad "42" smd rect
			(at -2.050034 -28.474924 90)
			(size 0.519938 1.4986)
			(layers "F.Cu" "F.Mask" "F.Paste")
			(net "M_G_CPU0_SA_DQ<25>")
		)
		(pad "43" smd rect
			(at -2.050034 -27.62504 90)
			(size 0.519938 1.4986)
			(layers "F.Cu" "F.Mask" "F.Paste")
			(net "GND")
		)
		(pad "44" smd rect
			(at -2.050034 -26.774902 90)
			(size 0.519938 1.4986)
			(layers "F.Cu" "F.Mask" "F.Paste")
			(net "M_G_CPU0_SA_DQS_DP<3>")
		)
		(pad "45" smd rect
			(at -2.050034 -25.925018 90)
			(size 0.519938 1.4986)
			(layers "F.Cu" "F.Mask" "F.Paste")
			(net "M_G_CPU0_SA_DQS_DN<3>")
		)
		(pad "46" smd rect
			(at -2.050034 -25.07488 90)
			(size 0.519938 1.4986)
			(layers "F.Cu" "F.Mask" "F.Paste")
			(net "GND")
		)
		(pad "47" smd rect
			(at -2.050034 -24.224996 90)
			(size 0.519938 1.4986)
			(layers "F.Cu" "F.Mask" "F.Paste")
			(net "M_G_CPU0_SA_DQ<28>")
		)
		(pad "48" smd rect
			(at -2.050034 -23.375112 90)
			(size 0.519938 1.4986)
			(layers "F.Cu" "F.Mask" "F.Paste")
			(net "GND")
		)
		(pad "49" smd rect
			(at -2.050034 -22.524974 90)
			(size 0.519938 1.4986)
			(layers "F.Cu" "F.Mask" "F.Paste")
			(net "M_G_CPU0_SA_DQ<29>")
		)
		(pad "50" smd rect
			(at -2.050034 -21.67509 90)
			(size 0.519938 1.4986)
			(layers "F.Cu" "F.Mask" "F.Paste")
			(net "GND")
		)
		(pad "51" smd rect
			(at -2.050034 -20.824952 90)
			(size 0.519938 1.4986)
			(layers "F.Cu" "F.Mask" "F.Paste")
			(net "M_G_CPU0_SA_CB<0>")
		)
		(pad "52" smd rect
			(at -2.050034 -19.975068 90)
			(size 0.519938 1.4986)
			(layers "F.Cu" "F.Mask" "F.Paste")
			(net "GND")
		)
		(pad "53" smd rect
			(at -2.050034 -19.12493 90)
			(size 0.519938 1.4986)
			(layers "F.Cu" "F.Mask" "F.Paste")
			(net "M_G_CPU0_SA_CB<1>")
		)
		(pad "54" smd rect
			(at -2.050034 -18.275046 90)
			(size 0.519938 1.4986)
			(layers "F.Cu" "F.Mask" "F.Paste")
			(net "GND")
		)
		(pad "55" smd rect
			(at -2.050034 -17.424908 90)
			(size 0.519938 1.4986)
			(layers "F.Cu" "F.Mask" "F.Paste")
			(net "M_G_CPU0_SA_DQS_DP<4>")
		)
		(pad "56" smd rect
			(at -2.050034 -16.575024 90)
			(size 0.519938 1.4986)
			(layers "F.Cu" "F.Mask" "F.Paste")
			(net "M_G_CPU0_SA_DQS_DN<4>")
		)
		(pad "57" smd rect
			(at -2.050034 -15.724886 90)
			(size 0.519938 1.4986)
			(layers "F.Cu" "F.Mask" "F.Paste")
			(net "GND")
		)
		(pad "58" smd rect
			(at -2.050034 -14.875002 90)
			(size 0.519938 1.4986)
			(layers "F.Cu" "F.Mask" "F.Paste")
			(net "M_G_CPU0_SA_CB<4>")
		)
		(pad "59" smd rect
			(at -2.050034 -14.025118 90)
			(size 0.519938 1.4986)
			(layers "F.Cu" "F.Mask" "F.Paste")
			(net "GND")
		)
		(pad "60" smd rect
			(at -2.050034 -13.17498 90)
			(size 0.519938 1.4986)
			(layers "F.Cu" "F.Mask" "F.Paste")
			(net "M_G_CPU0_SA_CB<5>")
		)
		(pad "61" smd rect
			(at -2.050034 -12.325096 90)
			(size 0.519938 1.4986)
			(layers "F.Cu" "F.Mask" "F.Paste")
			(net "GND")
		)
		(pad "62" smd rect
			(at -2.050034 -11.474958 90)
			(size 0.519938 1.4986)
			(layers "F.Cu" "F.Mask" "F.Paste")
			(net "M_G_CPU0_ALERT_N")
		)
		(pad "63" smd rect
			(at -2.050034 -10.625074 90)
			(size 0.519938 1.4986)
			(layers "F.Cu" "F.Mask" "F.Paste")
			(net "GND")
		)
		(pad "64" smd rect
			(at -2.050034 -9.774936 90)
			(size 0.519938 1.4986)
			(layers "F.Cu" "F.Mask" "F.Paste")
			(net "M_G_CPU0_SA_CS_N<0>")
		)
		(pad "65" smd rect
			(at -2.050034 -8.925052 90)
			(size 0.519938 1.4986)
			(layers "F.Cu" "F.Mask" "F.Paste")
			(net "GND")
		)
		(pad "66" smd rect
			(at -2.050034 -8.074914 90)
			(size 0.519938 1.4986)
			(layers "F.Cu" "F.Mask" "F.Paste")
			(net "M_G_CPU0_SA_CA<0>")
		)
		(pad "67" smd rect
			(at -2.050034 -7.22503 90)
			(size 0.519938 1.4986)
			(layers "F.Cu" "F.Mask" "F.Paste")
			(net "GND")
		)
		(pad "68" smd rect
			(at -2.050034 -6.374892 90)
			(size 0.519938 1.4986)
			(layers "F.Cu" "F.Mask" "F.Paste")
			(net "M_G_CPU0_SA_CA<2>")
		)
		(pad "69" smd rect
			(at -2.050034 -5.525008 90)
			(size 0.519938 1.4986)
			(layers "F.Cu" "F.Mask" "F.Paste")
			(net "GND")
		)
		(pad "70" smd rect
			(at -2.050034 -4.675124 90)
			(size 0.519938 1.4986)
			(layers "F.Cu" "F.Mask" "F.Paste")
			(net "M_G_CPU0_SA_CA<4>")
		)
		(pad "71" smd rect
			(at -2.050034 -3.824986 90)
			(size 0.519938 1.4986)
			(layers "F.Cu" "F.Mask" "F.Paste")
			(net "GND")
		)
		(pad "72" smd rect
			(at -2.050034 -2.975102 90)
			(size 0.519938 1.4986)
			(layers "F.Cu" "F.Mask" "F.Paste")
			(net "M_G_CPU0_SA_CA<6>")
		)
		(pad "73" smd rect
			(at -2.050034 -2.124964 90)
			(size 0.519938 1.4986)
			(layers "F.Cu" "F.Mask" "F.Paste")
			(net "GND")
		)
		(pad "74" smd rect
			(at -2.050034 -1.27508 90)
			(size 0.519938 1.4986)
			(layers "F.Cu" "F.Mask" "F.Paste")
			(net "M_G_CPU0_SA_PAR")
		)
		(pad "75" smd rect
			(at -2.050034 -0.424942 90)
			(size 0.519938 1.4986)
			(layers "F.Cu" "F.Mask" "F.Paste")
			(net "GND")
		)
		(pad "76" smd rect
			(at -2.050034 5.525008 90)
			(size 0.519938 1.4986)
			(layers "F.Cu" "F.Mask" "F.Paste")
			(net "M_G_CPU0_SB_CA<0>")
		)
		(pad "77" smd rect
			(at -2.050034 6.374892 90)
			(size 0.519938 1.4986)
			(layers "F.Cu" "F.Mask" "F.Paste")
			(net "GND")
		)
		(pad "78" smd rect
			(at -2.050034 7.22503 90)
			(size 0.519938 1.4986)
			(layers "F.Cu" "F.Mask" "F.Paste")
			(net "M_G_CPU0_SB_CA<2>")
		)
		(pad "79" smd rect
			(at -2.050034 8.074914 90)
			(size 0.519938 1.4986)
			(layers "F.Cu" "F.Mask" "F.Paste")
			(net "GND")
		)
		(pad "80" smd rect
			(at -2.050034 8.925052 90)
			(size 0.519938 1.4986)
			(layers "F.Cu" "F.Mask" "F.Paste")
			(net "M_G_CPU0_SB_CA<4>")
		)
		(pad "81" smd rect
			(at -2.050034 9.774936 90)
			(size 0.519938 1.4986)
			(layers "F.Cu" "F.Mask" "F.Paste")
			(net "GND")
		)
		(pad "82" smd rect
			(at -2.050034 10.625074 90)
			(size 0.519938 1.4986)
			(layers "F.Cu" "F.Mask" "F.Paste")
			(net "M_G_CPU0_SB_CA<6>")
		)
		(pad "83" smd rect
			(at -2.050034 11.474958 90)
			(size 0.519938 1.4986)
			(layers "F.Cu" "F.Mask" "F.Paste")
			(net "GND")
		)
		(pad "84" smd rect
			(at -2.050034 12.325096 90)
			(size 0.519938 1.4986)
			(layers "F.Cu" "F.Mask" "F.Paste")
			(net "M_G_CPU0_SB_CS_N<0>")
		)
		(pad "85" smd rect
			(at -2.050034 13.17498 90)
			(size 0.519938 1.4986)
			(layers "F.Cu" "F.Mask" "F.Paste")
			(net "GND")
		)
		(pad "86" smd rect
			(at -2.050034 14.025118 90)
			(size 0.519938 1.4986)
			(layers "F.Cu" "F.Mask" "F.Paste")
			(net "M_G_CPU0_SA_RSP<0>")
		)
		(pad "87" smd rect
			(at -2.050034 14.875002 90)
			(size 0.519938 1.4986)
			(layers "F.Cu" "F.Mask" "F.Paste")
			(net "M_G_CPU0_SB_RSP<0>")
		)
		(pad "88" smd rect
			(at -2.050034 15.724886 90)
			(size 0.519938 1.4986)
			(layers "F.Cu" "F.Mask" "F.Paste")
			(net "GND")
		)
		(pad "89" smd rect
			(at -2.050034 16.575024 90)
			(size 0.519938 1.4986)
			(layers "F.Cu" "F.Mask" "F.Paste")
			(net "M_G_CPU0_SB_CB<4>")
		)
		(pad "90" smd rect
			(at -2.050034 17.424908 90)
			(size 0.519938 1.4986)
			(layers "F.Cu" "F.Mask" "F.Paste")
			(net "GND")
		)
		(pad "91" smd rect
			(at -2.050034 18.275046 90)
			(size 0.519938 1.4986)
			(layers "F.Cu" "F.Mask" "F.Paste")
			(net "M_G_CPU0_SB_CB<5>")
		)
		(pad "92" smd rect
			(at -2.050034 19.12493 90)
			(size 0.519938 1.4986)
			(layers "F.Cu" "F.Mask" "F.Paste")
			(net "GND")
		)
		(pad "93" smd rect
			(at -2.050034 19.975068 90)
			(size 0.519938 1.4986)
			(layers "F.Cu" "F.Mask" "F.Paste")
			(net "M_G_CPU0_SB_DQS_DP<9>")
		)
		(pad "94" smd rect
			(at -2.050034 20.824952 90)
			(size 0.519938 1.4986)
			(layers "F.Cu" "F.Mask" "F.Paste")
			(net "M_G_CPU0_SB_DQS_DN<9>")
		)
		(pad "95" smd rect
			(at -2.050034 21.67509 90)
			(size 0.519938 1.4986)
			(layers "F.Cu" "F.Mask" "F.Paste")
			(net "GND")
		)
		(pad "96" smd rect
			(at -2.050034 22.524974 90)
			(size 0.519938 1.4986)
			(layers "F.Cu" "F.Mask" "F.Paste")
			(net "M_G_CPU0_SB_CB<0>")
		)
		(pad "97" smd rect
			(at -2.050034 23.375112 90)
			(size 0.519938 1.4986)
			(layers "F.Cu" "F.Mask" "F.Paste")
			(net "GND")
		)
		(pad "98" smd rect
			(at -2.050034 24.224996 90)
			(size 0.519938 1.4986)
			(layers "F.Cu" "F.Mask" "F.Paste")
			(net "M_G_CPU0_SB_CB<1>")
		)
		(pad "99" smd rect
			(at -2.050034 25.07488 90)
			(size 0.519938 1.4986)
			(layers "F.Cu" "F.Mask" "F.Paste")
			(net "GND")
		)
		(pad "100" smd rect
			(at -2.050034 25.925018 90)
			(size 0.519938 1.4986)
			(layers "F.Cu" "F.Mask" "F.Paste")
			(net "M_G_CPU0_SB_DQ<0>")
		)
		(pad "101" smd rect
			(at -2.050034 26.774902 90)
			(size 0.519938 1.4986)
			(layers "F.Cu" "F.Mask" "F.Paste")
			(net "GND")
		)
		(pad "102" smd rect
			(at -2.050034 27.62504 90)
			(size 0.519938 1.4986)
			(layers "F.Cu" "F.Mask" "F.Paste")
			(net "M_G_CPU0_SB_DQ<1>")
		)
		(pad "103" smd rect
			(at -2.050034 28.474924 90)
			(size 0.519938 1.4986)
			(layers "F.Cu" "F.Mask" "F.Paste")
			(net "GND")
		)
		(pad "104" smd rect
			(at -2.050034 29.325062 90)
			(size 0.519938 1.4986)
			(layers "F.Cu" "F.Mask" "F.Paste")
			(net "M_G_CPU0_SB_DQS_DP<0>")
		)
		(pad "105" smd rect
			(at -2.050034 30.174946 90)
			(size 0.519938 1.4986)
			(layers "F.Cu" "F.Mask" "F.Paste")
			(net "M_G_CPU0_SB_DQS_DN<0>")
		)
		(pad "106" smd rect
			(at -2.050034 31.025084 90)
			(size 0.519938 1.4986)
			(layers "F.Cu" "F.Mask" "F.Paste")
			(net "GND")
		)
		(pad "107" smd rect
			(at -2.050034 31.874968 90)
			(size 0.519938 1.4986)
			(layers "F.Cu" "F.Mask" "F.Paste")
			(net "M_G_CPU0_SB_DQ<4>")
		)
		(pad "108" smd rect
			(at -2.050034 32.725106 90)
			(size 0.519938 1.4986)
			(layers "F.Cu" "F.Mask" "F.Paste")
			(net "GND")
		)
		(pad "109" smd rect
			(at -2.050034 33.57499 90)
			(size 0.519938 1.4986)
			(layers "F.Cu" "F.Mask" "F.Paste")
			(net "M_G_CPU0_SB_DQ<5>")
		)
		(pad "110" smd rect
			(at -2.050034 34.425128 90)
			(size 0.519938 1.4986)
			(layers "F.Cu" "F.Mask" "F.Paste")
			(net "GND")
		)
		(pad "111" smd rect
			(at -2.050034 35.275012 90)
			(size 0.519938 1.4986)
			(layers "F.Cu" "F.Mask" "F.Paste")
			(net "M_G_CPU0_SB_DQ<8>")
		)
		(pad "112" smd rect
			(at -2.050034 36.124896 90)
			(size 0.519938 1.4986)
			(layers "F.Cu" "F.Mask" "F.Paste")
			(net "GND")
		)
		(pad "113" smd rect
			(at -2.050034 36.975034 90)
			(size 0.519938 1.4986)
			(layers "F.Cu" "F.Mask" "F.Paste")
			(net "M_G_CPU0_SB_DQ<9>")
		)
	)
)
